# T6G (Grand Teton) — schematic netlist excerpt (pin names and nets, part order shuffled) for the footprints in the layout excerpt that follows; sources: Cadence DE-HDL packaged netlist, KiCad conversion of 04192023_DAF0TMB3IC0_F0TG_MB_C_brd_V02_OCP.brd

C2499  Q_CAP  22UF 4V 20% X6S  pkg C0402  page 74 : A = PVDD11_S3_P1 ; B = GND
R154  Q_RES  1K 1% EMPTY  pkg 0402LF  page 210 : A = PVDD18_S5_P1 ; B = SVID_PVDDCR_CPU0_P1_SVTO

(kicad_pcb
	(version 20260206)
	(generator "pcbnew")
	(generator_version "10.0")
	(general
		(thickness 1.6)
		(legacy_teardrops no)
	)
	(paper "A4")
	(title_block
		(title "04192023_DAF0TMB3IC0_F0TG_MB_C_brd_V02_OCP.brd")
		(comment 1 "Grand Teton / footprints 4588-4589 of 8354")
	)
	(layers
		(0 "F.Cu" signal "TOP")
		(4 "In1.Cu" signal "GND")
		(6 "In2.Cu" signal "IN1")
		(8 "In3.Cu" signal "GND1")
		(10 "In4.Cu" signal "IN2")
		(12 "In5.Cu" signal "GND2")
		(14 "In6.Cu" signal "IN3")
		(16 "In7.Cu" signal "GND3")
		(18 "In8.Cu" signal "VCC")
		(20 "In9.Cu" signal "VCC1")
		(22 "In10.Cu" signal "GND4")
		(24 "In11.Cu" signal "IN4")
		(26 "In12.Cu" signal "GND5")
		(28 "In13.Cu" signal "IN5")
		(30 "In14.Cu" signal "GND6")
		(32 "In15.Cu" signal "IN6")
		(34 "In16.Cu" signal "GND7")
		(2 "B.Cu" signal "BOTTOM")
		(9 "F.Adhes" user "F.Adhesive")
		(11 "B.Adhes" user "B.Adhesive")
		(13 "F.Paste" user "Package Geometry/Pastemask Top")
		(15 "B.Paste" user "Package Geometry/Pastemask Bottom")
		(5 "F.SilkS" user "Ref Des/Silkscreen Top")
		(7 "B.SilkS" user "Ref Des/Silkscreen Bottom")
		(1 "F.Mask" user "Board Geometry/Soldermask Top")
		(3 "B.Mask" user "Board Geometry/Soldermask Bottom")
		(17 "Dwgs.User" user "User.Drawings")
		(19 "Cmts.User" user "User.Comments")
		(21 "Eco1.User" user "User.Eco1")
		(23 "Eco2.User" user "User.Eco2")
		(25 "Edge.Cuts" user "Board Geometry/Outline")
		(27 "Margin" user)
		(31 "F.CrtYd" user "Package Geometry/Place Bound Top")
		(29 "B.CrtYd" user "Package Geometry/Place Bound Bottom")
		(35 "F.Fab" user "Ref Des/Assembly Top")
		(33 "B.Fab" user "Ref Des/Assembly Bottom")
	)
	(footprint ""
		(layer "F.Cu")
		(at 112.427004 -261.748016 -90)
		(property "Reference" "C2499"
			(at 0 0 270)
			(layer "F.SilkS")
			(hide yes)
			(effects
				(font
					(size 1.27 1.27)
				)
			)
		)
		(property "Value" ""
			(at 0 0 270)
			(layer "F.Fab")
			(effects
				(font
					(size 1.27 1.27)
				)
			)
		)
		(duplicate_pad_numbers_are_jumpers no)
		(fp_line
			(start -0.7874 0.4064)
			(end -0.7874 -0.4064)
			(stroke
				(width 0.1524)
				(type default)
			)
			(layer "F.SilkS")
		)
		(fp_line
			(start 0.7874 0.4064)
			(end -0.7874 0.4064)
			(stroke
				(width 0.1524)
				(type default)
			)
			(layer "F.SilkS")
		)
		(fp_line
			(start -0.7874 -0.4064)
			(end 0.7874 -0.4064)
			(stroke
				(width 0.1524)
				(type default)
			)
			(layer "F.SilkS")
		)
		(fp_line
			(start 0.7874 -0.4064)
			(end 0.7874 0.4064)
			(stroke
				(width 0.1524)
				(type default)
			)
			(layer "F.SilkS")
		)
		(fp_line
			(start -0.67945 0.3048)
			(end -0.67945 -0.305054)
			(stroke
				(width 0.1)
				(type default)
			)
			(layer "F.Fab")
		)
		(fp_line
			(start -0.12065 0.3048)
			(end -0.67945 0.3048)
			(stroke
				(width 0.1)
				(type default)
			)
			(layer "F.Fab")
		)
		(fp_line
			(start 0.120396 0.3048)
			(end 0.120396 0.2794)
			(stroke
				(width 0.1)
				(type default)
			)
			(layer "F.Fab")
		)
		(fp_line
			(start 0.67945 0.3048)
			(end 0.120396 0.3048)
			(stroke
				(width 0.1)
				(type default)
			)
			(layer "F.Fab")
		)
		(fp_line
			(start -0.12065 0.2794)
			(end -0.12065 0.3048)
			(stroke
				(width 0.1)
				(type default)
			)
			(layer "F.Fab")
		)
		(fp_line
			(start 0.120396 0.2794)
			(end -0.12065 0.2794)
			(stroke
				(width 0.1)
				(type default)
			)
			(layer "F.Fab")
		)
		(fp_line
			(start -0.12065 -0.2794)
			(end 0.12065 -0.2794)
			(stroke
				(width 0.1)
				(type default)
			)
			(layer "F.Fab")
		)
		(fp_line
			(start 0.12065 -0.2794)
			(end 0.12065 -0.3048)
			(stroke
				(width 0.1)
				(type default)
			)
			(layer "F.Fab")
		)
		(fp_line
			(start 0.12065 -0.3048)
			(end 0.67945 -0.3048)
			(stroke
				(width 0.1)
				(type default)
			)
			(layer "F.Fab")
		)
		(fp_line
			(start 0.67945 -0.3048)
			(end 0.67945 0.3048)
			(stroke
				(width 0.1)
				(type default)
			)
			(layer "F.Fab")
		)
		(fp_line
			(start -0.67945 -0.305054)
			(end -0.12065 -0.305054)
			(stroke
				(width 0.1)
				(type default)
			)
			(layer "F.Fab")
		)
		(fp_line
			(start -0.12065 -0.305054)
			(end -0.12065 -0.2794)
			(stroke
				(width 0.1)
				(type default)
			)
			(layer "F.Fab")
		)
		(pad "1" smd circle
			(at -0.40005 0 270)
			(size 0 0)
			(layers "F.Cu" "F.Mask" "F.Paste")
			(net "PVDD11_S3_P1")
		)
		(pad "2" smd circle
			(at 0.40005 0 270)
			(size 0 0)
			(layers "F.Cu" "F.Mask" "F.Paste")
			(net "GND")
		)
	)
	(footprint ""
		(layer "F.Cu")
		(at 90.819478 -148.94941 180)
		(property "Reference" "R154"
			(at 0 0 180)
			(layer "F.SilkS")
			(hide yes)
			(effects
				(font
					(size 1.27 1.27)
				)
			)
		)
		(property "Value" ""
			(at 0 0 180)
			(layer "F.Fab")
			(effects
				(font
					(size 1.27 1.27)
				)
			)
		)
		(duplicate_pad_numbers_are_jumpers no)
		(fp_line
			(start 0.7874 0.4064)
			(end -0.7874 0.4064)
			(stroke
				(width 0.1524)
				(type default)
			)
			(layer "F.SilkS")
		)
		(fp_line
			(start 0.7874 -0.4064)
			(end 0.7874 0.4064)
			(stroke
				(width 0.1524)
				(type default)
			)
			(layer "F.SilkS")
		)
		(fp_line
			(start -0.7874 0.4064)
			(end -0.7874 -0.4064)
			(stroke
				(width 0.1524)
				(type default)
			)
			(layer "F.SilkS")
		)
		(fp_line
			(start -0.7874 -0.4064)
			(end 0.7874 -0.4064)
			(stroke
				(width 0.1524)
				(type default)
			)
			(layer "F.SilkS")
		)
		(fp_line
			(start 0.67945 0.3048)
			(end 0.120396 0.3048)
			(stroke
				(width 0.1)
				(type default)
			)
			(layer "F.Fab")
		)
		(fp_line
			(start 0.67945 -0.3048)
			(end 0.67945 0.3048)
			(stroke
				(width 0.1)
				(type default)
			)
			(layer "F.Fab")
		)
		(fp_line
			(start 0.12065 -0.2794)
			(end 0.12065 -0.3048)
			(stroke
				(width 0.1)
				(type default)
			)
			(layer "F.Fab")
		)
		(fp_line
			(start 0.12065 -0.3048)
			(end 0.67945 -0.3048)
			(stroke
				(width 0.1)
				(type default)
			)
			(layer "F.Fab")
		)
		(fp_line
			(start 0.120396 0.3048)
			(end 0.120396 0.2794)
			(stroke
				(width 0.1)
				(type default)
			)
			(layer "F.Fab")
		)
		(fp_line
			(start 0.120396 0.2794)
			(end -0.12065 0.2794)
			(stroke
				(width 0.1)
				(type default)
			)
			(layer "F.Fab")
		)
		(fp_line
			(start -0.12065 0.3048)
			(end -0.67945 0.3048)
			(stroke
				(width 0.1)
				(type default)
			)
			(layer "F.Fab")
		)
		(fp_line
			(start -0.12065 0.2794)
			(end -0.12065 0.3048)
			(stroke
				(width 0.1)
				(type default)
			)
			(layer "F.Fab")
		)
		(fp_line
			(start -0.12065 -0.2794)
			(end 0.12065 -0.2794)
			(stroke
				(width 0.1)
				(type default)
			)
			(layer "F.Fab")
		)
		(fp_line
			(start -0.12065 -0.305054)
			(end -0.12065 -0.2794)
			(stroke
				(width 0.1)
				(type default)
			)
			(layer "F.Fab")
		)
		(fp_line
			(start -0.67945 0.3048)
			(end -0.67945 -0.305054)
			(stroke
				(width 0.1)
				(type default)
			)
			(layer "F.Fab")
		)
		(fp_line
			(start -0.67945 -0.305054)
			(end -0.12065 -0.305054)
			(stroke
				(width 0.1)
				(type default)
			)
			(layer "F.Fab")
		)
		(pad "1" smd circle
			(at -0.40005 0 180)
			(size 0 0)
			(layers "F.Cu" "F.Mask" "F.Paste")
			(net "PVDD18_S5_P1")
		)
		(pad "2" smd circle
			(at 0.40005 0 180)
			(size 0 0)
			(layers "F.Cu" "F.Mask" "F.Paste")
			(net "SVID_PVDDCR_CPU0_P1_SVTO")
		)
	)
)
